#ISCELL
  logical_power cad_note *
  *
#ISCELL
  mstr_misc dns *
  *
#ISCELL
  pure_quanta quanta_title_block_c *
  *
#ISCELL
  logical_power universal_gnd *
  page53_i10
#ISCELL
  logical_power universal_gnd *
  page53_i16
#ISCELL
  logical_power vccaux15 *
  page53_i2
#ISCELL
  logical_power universal_gnd *
  page53_i26
#ISCELL
  logical_power vccaux15 *
  page53_i29
#ISCELL
  logical_power vccaux15 *
  page53_i45
#ISCELL
  logical_power vccaux15 *
  page53_i48
#ISCELL
  logical_power universal_gnd *
  page53_i50
#ISCELL
  standard offpage *
  page53_i54
#CELL
  pure_quanta q_res *
  page53_i58
#CELL
  pure_quanta rt9059gqw *
  page53_i60
#CELL
  pure_quanta q_res *
  page53_i61
#CELL
  pure_quanta q_res *
  page53_i62
#ISCELL
  logical_power universal_gnd *
  page53_i63
#CELL
  pure_quanta q_cap *
  page53_i64
#CELL
  pure_quanta q_res *
  page53_i65
#ISCELL
  standard offpage *
  page53_i66
#CELL
  pure_quanta q_cap *
  page53_i67
#CELL
  pure_quanta q_res *
  page53_i68
#CELL
  pure_quanta q_cap *
  page53_i69
#CELL
  pure_quanta q_cap *
  page53_i70
#CELL
  pure_quanta q_cap *
  page53_i71
#CELL
  pure_quanta q_res *
  page53_i72
#ISCELL
  standard offpage *
  page53_i73
